(kicad_pcb
	(version 20241229)
	(generator "pcbnew")
	(generator_version "9.0")
	(general
		(thickness 1.599998)
		(legacy_teardrops no)
	)
	(paper "A4")
	(title_block
		(title "Artix - Datacenter Secure Control Module (DC-SCM)")
		(date "2024-11-06")
		(rev "1.1.3")
		(comment 9 "footprints 264-265 of 544")
	)
	(layers
		(0 "F.Cu" signal)
		(4 "In1.Cu" signal)
		(6 "In2.Cu" signal)
		(8 "In3.Cu" signal)
		(10 "In4.Cu" signal)
		(12 "In5.Cu" signal)
		(14 "In6.Cu" signal)
		(2 "B.Cu" signal)
		(9 "F.Adhes" user "F.Adhesive")
		(11 "B.Adhes" user "B.Adhesive")
		(13 "F.Paste" user)
		(15 "B.Paste" user)
		(5 "F.SilkS" user "F.Silkscreen")
		(7 "B.SilkS" user "B.Silkscreen")
		(1 "F.Mask" user)
		(3 "B.Mask" user)
		(17 "Dwgs.User" user "User.Drawings")
		(19 "Cmts.User" user "User.Comments")
		(21 "Eco1.User" user "User.Eco1")
		(23 "Eco2.User" user "User.Eco2")
		(25 "Edge.Cuts" user)
		(27 "Margin" user)
		(31 "F.CrtYd" user "F.Courtyard")
		(29 "B.CrtYd" user "B.Courtyard")
		(35 "F.Fab" user)
		(33 "B.Fab" user)
	)
	(footprint "antmicro-footprints:Spacer_Drill3.7mm_H2.5mm_9774025151R"
		(locked yes)
		(layer "F.Cu")
		(at 125.97 81.38)
		(descr "Spacer M=3 h=2.5mm fi=5.1mm")
		(property "Reference" "H1"
			(at 0 -3.2 0)
			(layer "F.SilkS")
			(effects
				(font
					(size 0.7 0.7)
					(thickness 0.15)
				)
				(justify left bottom)
			)
		)
		(property "Value" "Spacer_Drill3.7mm_H2.5mm_9774025151R"
			(at 0 4 0)
			(layer "F.Fab")
			(effects
				(font
					(size 0.7 0.7)
					(thickness 0.15)
				)
				(justify left bottom)
			)
		)
		(property "Datasheet" "https://www.we-online.com/components/products/datasheet/9774025151R.pdf"
			(at 0 0 0)
			(layer "F.Fab")
			(hide yes)
			(effects
				(font
					(size 1.27 1.27)
					(thickness 0.15)
				)
			)
		)
		(property "Description" "Spacer, SMT, Non Stop, Steel, Swage Round, 5.1 mm x 2.5 mm, M2.5 Thread, WA-SMSI Series"
			(at 0 0 0)
			(layer "F.Fab")
			(hide yes)
			(effects
				(font
					(size 1.27 1.27)
					(thickness 0.15)
				)
			)
		)
		(property "Author" "Antmicro"
			(at 0 0 0)
			(layer "F.Fab")
			(hide yes)
			(effects
				(font
					(size 1 1)
					(thickness 0.15)
				)
			)
		)
		(property "License" "Apache-2.0"
			(at 0 0 0)
			(layer "F.Fab")
			(hide yes)
			(effects
				(font
					(size 1 1)
					(thickness 0.15)
				)
			)
		)
		(property "MPN" "9774025151R"
			(at 0 0 0)
			(layer "F.Fab")
			(hide yes)
			(effects
				(font
					(size 1 1)
					(thickness 0.15)
				)
			)
		)
		(property "Manufacturer" "Würth Elektronik"
			(at 0 0 0)
			(layer "F.Fab")
			(hide yes)
			(effects
				(font
					(size 1 1)
					(thickness 0.15)
				)
			)
		)
		(sheetname "/PCIe-connector/")
		(sheetfile "pcie-conn.kicad_sch")
		(solder_paste_margin_ratio -1)
		(attr smd)
		(fp_circle
			(center 0 0)
			(end 3.05 0)
			(stroke
				(width 0.05)
				(type solid)
			)
			(fill no)
			(layer "F.CrtYd")
		)
		(fp_circle
			(center 0 0)
			(end 2.6 0)
			(stroke
				(width 0.15)
				(type solid)
			)
			(fill no)
			(layer "F.Fab")
		)
		(pad "" smd custom
			(at -1.7 -1.7)
			(size 0.62 0.62)
			(layers "F.Paste")
			(thermal_bridge_angle 90)
			(options
				(clearance outline)
				(anchor circle)
			)
			(primitives
				(gr_arc
					(start -0.250195 1.279127)
					(mid 0.285453 0.294389)
					(end 1.266786 -0.24747)
					(width 0.2)
				)
				(gr_arc
					(start -0.34334 1.279127)
					(mid 0.218448 0.232561)
					(end 1.259603 -0.339191)
					(width 0.2)
				)
				(gr_arc
					(start -0.436309 1.279127)
					(mid 0.152481 0.169693)
					(end 1.255279 -0.431435)
					(width 0.2)
				)
				(gr_arc
					(start -0.529126 1.279127)
					(mid 0.087542 0.105784)
					(end 1.253811 -0.524161)
					(width 0.2)
				)
				(gr_arc
					(start -0.621807 1.279127)
					(mid 0.0309 0.033527)
					(end 1.275473 -0.621136)
					(width 0.2)
				)
				(gr_arc
					(start -0.71437 1.279127)
					(mid -0.037758 -0.026651)
					(end 1.263664 -0.711602)
					(width 0.2)
				)
				(gr_arc
					(start -0.806826 1.279127)
					(mid -0.105837 -0.087395)
					(end 1.253435 -0.802342)
					(width 0.2)
				)
				(gr_arc
					(start -0.899187 1.279127)
					(mid -0.165236 -0.156885)
					(end 1.267475 -0.897258)
					(width 0.2)
				)
				(gr_arc
					(start -0.991463 1.279127)
					(mid -0.228522 -0.222449)
					(end 1.270645 -0.990112)
					(width 0.2)
				)
				(gr_arc
					(start -1.083663 1.279127)
					(mid -0.294507 -0.285313)
					(end 1.266278 -1.081674)
					(width 0.2)
				)
				(gr_line
					(start 1.279127 -0.250195)
					(end 1.279127 -1.083663)
					(width 0.2)
				)
				(gr_line
					(start -0.250195 1.279127)
					(end -1.083663 1.279127)
					(width 0.2)
				)
			)
		)
		(pad "" smd custom
			(at -1.7 1.7 90)
			(size 0.62 0.62)
			(layers "F.Paste")
			(thermal_bridge_angle 90)
			(options
				(clearance outline)
				(anchor circle)
			)
			(primitives
				(gr_arc
					(start -0.250195 1.279127)
					(mid 0.285453 0.294389)
					(end 1.266786 -0.24747)
					(width 0.2)
				)
				(gr_arc
					(start -0.34334 1.279127)
					(mid 0.218448 0.232561)
					(end 1.259603 -0.339191)
					(width 0.2)
				)
				(gr_arc
					(start -0.436309 1.279127)
					(mid 0.152481 0.169693)
					(end 1.255279 -0.431435)
					(width 0.2)
				)
				(gr_arc
					(start -0.529126 1.279127)
					(mid 0.087542 0.105784)
					(end 1.253811 -0.524161)
					(width 0.2)
				)
				(gr_arc
					(start -0.621807 1.279127)
					(mid 0.0309 0.033527)
					(end 1.275473 -0.621136)
					(width 0.2)
				)
				(gr_arc
					(start -0.71437 1.279127)
					(mid -0.037758 -0.026651)
					(end 1.263664 -0.711602)
					(width 0.2)
				)
				(gr_arc
					(start -0.806826 1.279127)
					(mid -0.105837 -0.087395)
					(end 1.253435 -0.802342)
					(width 0.2)
				)
				(gr_arc
					(start -0.899187 1.279127)
					(mid -0.165236 -0.156885)
					(end 1.267475 -0.897258)
					(width 0.2)
				)
				(gr_arc
					(start -0.991463 1.279127)
					(mid -0.228522 -0.222449)
					(end 1.270645 -0.990112)
					(width 0.2)
				)
				(gr_arc
					(start -1.083663 1.279127)
					(mid -0.294507 -0.285313)
					(end 1.266278 -1.081674)
					(width 0.2)
				)
				(gr_line
					(start 1.279127 -0.250195)
					(end 1.279127 -1.083663)
					(width 0.2)
				)
				(gr_line
					(start -0.250195 1.279127)
					(end -1.083663 1.279127)
					(width 0.2)
				)
			)
		)
		(pad "" smd custom
			(at 1.7 -1.7 270)
			(size 0.62 0.62)
			(layers "F.Paste")
			(thermal_bridge_angle 90)
			(options
				(clearance outline)
				(anchor circle)
			)
			(primitives
				(gr_arc
					(start -0.250195 1.279127)
					(mid 0.285453 0.294389)
					(end 1.266786 -0.24747)
					(width 0.2)
				)
				(gr_arc
					(start -0.34334 1.279127)
					(mid 0.218448 0.232561)
					(end 1.259603 -0.339191)
					(width 0.2)
				)
				(gr_arc
					(start -0.436309 1.279127)
					(mid 0.152481 0.169693)
					(end 1.255279 -0.431435)
					(width 0.2)
				)
				(gr_arc
					(start -0.529126 1.279127)
					(mid 0.087542 0.105784)
					(end 1.253811 -0.524161)
					(width 0.2)
				)
				(gr_arc
					(start -0.621807 1.279127)
					(mid 0.0309 0.033527)
					(end 1.275473 -0.621136)
					(width 0.2)
				)
				(gr_arc
					(start -0.71437 1.279127)
					(mid -0.037758 -0.026651)
					(end 1.263664 -0.711602)
					(width 0.2)
				)
				(gr_arc
					(start -0.806826 1.279127)
					(mid -0.105837 -0.087395)
					(end 1.253435 -0.802342)
					(width 0.2)
				)
				(gr_arc
					(start -0.899187 1.279127)
					(mid -0.165236 -0.156885)
					(end 1.267475 -0.897258)
					(width 0.2)
				)
				(gr_arc
					(start -0.991463 1.279127)
					(mid -0.228522 -0.222449)
					(end 1.270645 -0.990112)
					(width 0.2)
				)
				(gr_arc
					(start -1.083663 1.279127)
					(mid -0.294507 -0.285313)
					(end 1.266278 -1.081674)
					(width 0.2)
				)
				(gr_line
					(start 1.279127 -0.250195)
					(end 1.279127 -1.083663)
					(width 0.2)
				)
				(gr_line
					(start -0.250195 1.279127)
					(end -1.083663 1.279127)
					(width 0.2)
				)
			)
		)
		(pad "" smd custom
			(at 1.7 1.7 180)
			(size 0.62 0.62)
			(layers "F.Paste")
			(thermal_bridge_angle 90)
			(options
				(clearance outline)
				(anchor circle)
			)
			(primitives
				(gr_arc
					(start -0.250195 1.279127)
					(mid 0.285453 0.294389)
					(end 1.266786 -0.24747)
					(width 0.2)
				)
				(gr_arc
					(start -0.34334 1.279127)
					(mid 0.218448 0.232561)
					(end 1.259603 -0.339191)
					(width 0.2)
				)
				(gr_arc
					(start -0.436309 1.279127)
					(mid 0.152481 0.169693)
					(end 1.255279 -0.431435)
					(width 0.2)
				)
				(gr_arc
					(start -0.529126 1.279127)
					(mid 0.087542 0.105784)
					(end 1.253811 -0.524161)
					(width 0.2)
				)
				(gr_arc
					(start -0.621807 1.279127)
					(mid 0.0309 0.033527)
					(end 1.275473 -0.621136)
					(width 0.2)
				)
				(gr_arc
					(start -0.71437 1.279127)
					(mid -0.037758 -0.026651)
					(end 1.263664 -0.711602)
					(width 0.2)
				)
				(gr_arc
					(start -0.806826 1.279127)
					(mid -0.105837 -0.087395)
					(end 1.253435 -0.802342)
					(width 0.2)
				)
				(gr_arc
					(start -0.899187 1.279127)
					(mid -0.165236 -0.156885)
					(end 1.267475 -0.897258)
					(width 0.2)
				)
				(gr_arc
					(start -0.991463 1.279127)
					(mid -0.228522 -0.222449)
					(end 1.270645 -0.990112)
					(width 0.2)
				)
				(gr_arc
					(start -1.083663 1.279127)
					(mid -0.294507 -0.285313)
					(end 1.266278 -1.081674)
					(width 0.2)
				)
				(gr_line
					(start 1.279127 -0.250195)
					(end 1.279127 -1.083663)
					(width 0.2)
				)
				(gr_line
					(start -0.250195 1.279127)
					(end -1.083663 1.279127)
					(width 0.2)
				)
			)
		)
		(pad "1" thru_hole circle
			(at 0 0)
			(size 6 6)
			(drill 3.7)
			(layers "*.Cu" "*.Mask")
			(remove_unused_layers no)
			(net 692 "unconnected-(H1-Pad1)")
			(pintype "passive+no_connect")
		)
	)
	(footprint "antmicro-footprints:Spacer_Drill3.7mm_H4mm_9774040151R"
		(layer "F.Cu")
		(at 73.82 112.4)
		(descr "Spacer M=3 h=4mm fi=5.1mm")
		(property "Reference" "H2"
			(at 0 -3.2 0)
			(layer "F.SilkS")
			(effects
				(font
					(size 0.7 0.7)
					(thickness 0.15)
				)
				(justify left bottom)
			)
		)
		(property "Value" "Spacer_Drill3.7mm_H4mm_9774040151R"
			(at 0 4 0)
			(layer "F.Fab")
			(effects
				(font
					(size 0.7 0.7)
					(thickness 0.15)
				)
				(justify left bottom)
			)
		)
		(property "Datasheet" "https://www.we-online.com/components/products/datasheet/9774040151R.pdf"
			(at 0 0 0)
			(layer "F.Fab")
			(hide yes)
			(effects
				(font
					(size 1.27 1.27)
					(thickness 0.15)
				)
			)
		)
		(property "Description" "Round Standoff Threaded M2.5x0.45 Steel 0.157\" (4.00mm)"
			(at 0 0 0)
			(layer "F.Fab")
			(hide yes)
			(effects
				(font
					(size 1.27 1.27)
					(thickness 0.15)
				)
			)
		)
		(property "Author" "Antmicro"
			(at 0 0 0)
			(layer "F.Fab")
			(hide yes)
			(effects
				(font
					(size 1 1)
					(thickness 0.15)
				)
			)
		)
		(property "License" "Apache-2.0"
			(at 0 0 0)
			(layer "F.Fab")
			(hide yes)
			(effects
				(font
					(size 1 1)
					(thickness 0.15)
				)
			)
		)
		(property "MPN" "9774040151R"
			(at 0 0 0)
			(layer "F.Fab")
			(hide yes)
			(effects
				(font
					(size 1 1)
					(thickness 0.15)
				)
			)
		)
		(property "Manufacturer" "Würth Elektronik"
			(at 0 0 0)
			(layer "F.Fab")
			(hide yes)
			(effects
				(font
					(size 1 1)
					(thickness 0.15)
				)
			)
		)
		(sheetname "/RoT/")
		(sheetfile "rot.kicad_sch")
		(solder_paste_margin_ratio -1)
		(attr smd)
		(fp_circle
			(center 0 0)
			(end 3.05 0)
			(stroke
				(width 0.05)
				(type solid)
			)
			(fill no)
			(layer "F.CrtYd")
		)
		(fp_circle
			(center 0 0)
			(end 2.6 0)
			(stroke
				(width 0.15)
				(type solid)
			)
			(fill no)
			(layer "F.Fab")
		)
		(pad "" smd custom
			(at -1.7 -1.7)
			(size 0.62 0.62)
			(layers "F.Paste")
			(thermal_bridge_angle 90)
			(options
				(clearance outline)
				(anchor circle)
			)
			(primitives
				(gr_arc
					(start -0.250195 1.279127)
					(mid 0.285453 0.294389)
					(end 1.266786 -0.24747)
					(width 0.2)
				)
				(gr_arc
					(start -0.34334 1.279127)
					(mid 0.218448 0.232561)
					(end 1.259603 -0.339191)
					(width 0.2)
				)
				(gr_arc
					(start -0.436309 1.279127)
					(mid 0.152481 0.169693)
					(end 1.255279 -0.431435)
					(width 0.2)
				)
				(gr_arc
					(start -0.529126 1.279127)
					(mid 0.087542 0.105784)
					(end 1.253811 -0.524161)
					(width 0.2)
				)
				(gr_arc
					(start -0.621807 1.279127)
					(mid 0.0309 0.033527)
					(end 1.275473 -0.621136)
					(width 0.2)
				)
				(gr_arc
					(start -0.71437 1.279127)
					(mid -0.037758 -0.026651)
					(end 1.263664 -0.711602)
					(width 0.2)
				)
				(gr_arc
					(start -0.806826 1.279127)
					(mid -0.105837 -0.087395)
					(end 1.253435 -0.802342)
					(width 0.2)
				)
				(gr_arc
					(start -0.899187 1.279127)
					(mid -0.165236 -0.156885)
					(end 1.267475 -0.897258)
					(width 0.2)
				)
				(gr_arc
					(start -0.991463 1.279127)
					(mid -0.228522 -0.222449)
					(end 1.270645 -0.990112)
					(width 0.2)
				)
				(gr_arc
					(start -1.083663 1.279127)
					(mid -0.294507 -0.285313)
					(end 1.266278 -1.081674)
					(width 0.2)
				)
				(gr_line
					(start 1.279127 -0.250195)
					(end 1.279127 -1.083663)
					(width 0.2)
				)
				(gr_line
					(start -0.250195 1.279127)
					(end -1.083663 1.279127)
					(width 0.2)
				)
			)
		)
		(pad "" smd custom
			(at -1.7 1.7 90)
			(size 0.62 0.62)
			(layers "F.Paste")
			(thermal_bridge_angle 90)
			(options
				(clearance outline)
				(anchor circle)
			)
			(primitives
				(gr_arc
					(start -0.250195 1.279127)
					(mid 0.285453 0.294389)
					(end 1.266786 -0.24747)
					(width 0.2)
				)
				(gr_arc
					(start -0.34334 1.279127)
					(mid 0.218448 0.232561)
					(end 1.259603 -0.339191)
					(width 0.2)
				)
				(gr_arc
					(start -0.436309 1.279127)
					(mid 0.152481 0.169693)
					(end 1.255279 -0.431435)
					(width 0.2)
				)
				(gr_arc
					(start -0.529126 1.279127)
					(mid 0.087542 0.105784)
					(end 1.253811 -0.524161)
					(width 0.2)
				)
				(gr_arc
					(start -0.621807 1.279127)
					(mid 0.0309 0.033527)
					(end 1.275473 -0.621136)
					(width 0.2)
				)
				(gr_arc
					(start -0.71437 1.279127)
					(mid -0.037758 -0.026651)
					(end 1.263664 -0.711602)
					(width 0.2)
				)
				(gr_arc
					(start -0.806826 1.279127)
					(mid -0.105837 -0.087395)
					(end 1.253435 -0.802342)
					(width 0.2)
				)
				(gr_arc
					(start -0.899187 1.279127)
					(mid -0.165236 -0.156885)
					(end 1.267475 -0.897258)
					(width 0.2)
				)
				(gr_arc
					(start -0.991463 1.279127)
					(mid -0.228522 -0.222449)
					(end 1.270645 -0.990112)
					(width 0.2)
				)
				(gr_arc
					(start -1.083663 1.279127)
					(mid -0.294507 -0.285313)
					(end 1.266278 -1.081674)
					(width 0.2)
				)
				(gr_line
					(start 1.279127 -0.250195)
					(end 1.279127 -1.083663)
					(width 0.2)
				)
				(gr_line
					(start -0.250195 1.279127)
					(end -1.083663 1.279127)
					(width 0.2)
				)
			)
		)
		(pad "" smd custom
			(at 1.7 -1.7 270)
			(size 0.62 0.62)
			(layers "F.Paste")
			(thermal_bridge_angle 90)
			(options
				(clearance outline)
				(anchor circle)
			)
			(primitives
				(gr_arc
					(start -0.250195 1.279127)
					(mid 0.285453 0.294389)
					(end 1.266786 -0.24747)
					(width 0.2)
				)
				(gr_arc
					(start -0.34334 1.279127)
					(mid 0.218448 0.232561)
					(end 1.259603 -0.339191)
					(width 0.2)
				)
				(gr_arc
					(start -0.436309 1.279127)
					(mid 0.152481 0.169693)
					(end 1.255279 -0.431435)
					(width 0.2)
				)
				(gr_arc
					(start -0.529126 1.279127)
					(mid 0.087542 0.105784)
					(end 1.253811 -0.524161)
					(width 0.2)
				)
				(gr_arc
					(start -0.621807 1.279127)
					(mid 0.0309 0.033527)
					(end 1.275473 -0.621136)
					(width 0.2)
				)
				(gr_arc
					(start -0.71437 1.279127)
					(mid -0.037758 -0.026651)
					(end 1.263664 -0.711602)
					(width 0.2)
				)
				(gr_arc
					(start -0.806826 1.279127)
					(mid -0.105837 -0.087395)
					(end 1.253435 -0.802342)
					(width 0.2)
				)
				(gr_arc
					(start -0.899187 1.279127)
					(mid -0.165236 -0.156885)
					(end 1.267475 -0.897258)
					(width 0.2)
				)
				(gr_arc
					(start -0.991463 1.279127)
					(mid -0.228522 -0.222449)
					(end 1.270645 -0.990112)
					(width 0.2)
				)
				(gr_arc
					(start -1.083663 1.279127)
					(mid -0.294507 -0.285313)
					(end 1.266278 -1.081674)
					(width 0.2)
				)
				(gr_line
					(start 1.279127 -0.250195)
					(end 1.279127 -1.083663)
					(width 0.2)
				)
				(gr_line
					(start -0.250195 1.279127)
					(end -1.083663 1.279127)
					(width 0.2)
				)
			)
		)
		(pad "" smd custom
			(at 1.7 1.7 180)
			(size 0.62 0.62)
			(layers "F.Paste")
			(thermal_bridge_angle 90)
			(options
				(clearance outline)
				(anchor circle)
			)
			(primitives
				(gr_arc
					(start -0.250195 1.279127)
					(mid 0.285453 0.294389)
					(end 1.266786 -0.24747)
					(width 0.2)
				)
				(gr_arc
					(start -0.34334 1.279127)
					(mid 0.218448 0.232561)
					(end 1.259603 -0.339191)
					(width 0.2)
				)
				(gr_arc
					(start -0.436309 1.279127)
					(mid 0.152481 0.169693)
					(end 1.255279 -0.431435)
					(width 0.2)
				)
				(gr_arc
					(start -0.529126 1.279127)
					(mid 0.087542 0.105784)
					(end 1.253811 -0.524161)
					(width 0.2)
				)
				(gr_arc
					(start -0.621807 1.279127)
					(mid 0.0309 0.033527)
					(end 1.275473 -0.621136)
					(width 0.2)
				)
				(gr_arc
					(start -0.71437 1.279127)
					(mid -0.037758 -0.026651)
					(end 1.263664 -0.711602)
					(width 0.2)
				)
				(gr_arc
					(start -0.806826 1.279127)
					(mid -0.105837 -0.087395)
					(end 1.253435 -0.802342)
					(width 0.2)
				)
				(gr_arc
					(start -0.899187 1.279127)
					(mid -0.165236 -0.156885)
					(end 1.267475 -0.897258)
					(width 0.2)
				)
				(gr_arc
					(start -0.991463 1.279127)
					(mid -0.228522 -0.222449)
					(end 1.270645 -0.990112)
					(width 0.2)
				)
				(gr_arc
					(start -1.083663 1.279127)
					(mid -0.294507 -0.285313)
					(end 1.266278 -1.081674)
					(width 0.2)
				)
				(gr_line
					(start 1.279127 -0.250195)
					(end 1.279127 -1.083663)
					(width 0.2)
				)
				(gr_line
					(start -0.250195 1.279127)
					(end -1.083663 1.279127)
					(width 0.2)
				)
			)
		)
		(pad "1" thru_hole circle
			(at 0 0)
			(size 6 6)
			(drill 3.7)
			(layers "*.Cu" "*.Mask")
			(remove_unused_layers no)
			(net 693 "unconnected-(H2-Pad1)")
			(pintype "passive+no_connect")
		)
	)
)
